# T6G (Grand Teton) — schematic netlist excerpt (pin names and nets, part order shuffled) for the footprints in the layout excerpt that follows; sources: Cadence DE-HDL packaged netlist, KiCad conversion of 04192023_DAF0TMB3IC0_F0TG_MB_C_brd_V02_OCP.brd

J18  SCONN288_DDR506112002KQ  IO  pkg DDR288S_1-1VXC  page 94
  VIN_BULK0  = P12V_MEM_CPU0
  RFU0  = NC
  VIN_MGMT  = P3V3_AUX
  HSCL  = I3C_SPD_DDRI_CPU0_SCL
  HSDA  = I3C_SPD_DDRI_CPU0_SDA
  VSS0  = GND
  DQ0_A  = M_I_CPU0_SA_DQ<0>
  VSS1  = GND
  DQ1_A  = M_I_CPU0_SA_DQ<1>
  VSS2  = GND
  DQS0_A_T  = M_I_CPU0_SA_DQS_DP<0>
  DQS0_A_C  = M_I_CPU0_SA_DQS_DN<0>
  VSS3  = GND
  DQ4_A  = M_I_CPU0_SA_DQ<4>
  VSS4  = GND
  DQ5_A  = M_I_CPU0_SA_DQ<5>
  VSS5  = GND
  DQ8_A  = M_I_CPU0_SA_DQ<8>
  VSS6  = GND
  DQ9_A  = M_I_CPU0_SA_DQ<9>
  VSS7  = GND
  DQS1_A_T  = M_I_CPU0_SA_DQS_DP<1>
  DQS1_A_C  = M_I_CPU0_SA_DQS_DN<1>
  VSS8  = GND
  DQ12_A  = M_I_CPU0_SA_DQ<12>
  VSS9  = GND
  DQ13_A  = M_I_CPU0_SA_DQ<13>
  VSS10  = GND
  DQ16_A  = M_I_CPU0_SA_DQ<16>
  VSS11  = GND
  DQ17_A  = M_I_CPU0_SA_DQ<17>
  VSS12  = GND
  DQS2_A_T  = M_I_CPU0_SA_DQS_DP<2>
  DQS2_A_C  = M_I_CPU0_SA_DQS_DN<2>
  VSS13  = GND
  DQ20_A  = M_I_CPU0_SA_DQ<20>
  VSS14  = GND
  DQ21_A  = M_I_CPU0_SA_DQ<21>
  VSS15  = GND
  DQ24_A  = M_I_CPU0_SA_DQ<24>
  VSS16  = GND
  DQ25_A  = M_I_CPU0_SA_DQ<25>
  VSS17  = GND
  DQS3_A_T  = M_I_CPU0_SA_DQS_DP<3>
  DQS3_A_C  = M_I_CPU0_SA_DQS_DN<3>
  VSS18  = GND
  DQ28_A  = M_I_CPU0_SA_DQ<28>
  VSS19  = GND
  DQ29_A  = M_I_CPU0_SA_DQ<29>
  VSS20  = GND
  CB0_A  = M_I_CPU0_SA_CB<0>
  VSS21  = GND
  CB1_A  = M_I_CPU0_SA_CB<1>
  VSS22  = GND
  DQS4_A_T  = M_I_CPU0_SA_DQS_DP<4>
  DQS4_A_C  = M_I_CPU0_SA_DQS_DN<4>
  VSS23  = GND
  CB4_A  = M_I_CPU0_SA_CB<4>
  VSS24  = GND
  CB5_A  = M_I_CPU0_SA_CB<5>
  VSS25  = GND
  ALERT_N  = M_I_CPU0_ALERT_N
  VSS26  = GND
  CS0_A_N  = M_I_CPU0_SA_CS_N<0>
  VSS27  = GND
  CA0_A  = M_I_CPU0_SA_CA<0>
  VSS28  = GND
  CA2_A  = M_I_CPU0_SA_CA<2>
  VSS29  = GND
  CA4_A  = M_I_CPU0_SA_CA<4>
  VSS30  = GND
  CA6_A  = M_I_CPU0_SA_CA<6>
  VSS31  = GND
  PAR_A  = M_I_CPU0_SA_PAR
  VSS32  = GND
  CA0_B  = M_I_CPU0_SB_CA<0>
  VSS33  = GND
  CA2_B  = M_I_CPU0_SB_CA<2>
  VSS34  = GND
  CA4_B  = M_I_CPU0_SB_CA<4>
  VSS35  = GND
  CA6_B  = M_I_CPU0_SB_CA<6>
  VSS36  = GND
  CS0_B_N  = M_I_CPU0_SB_CS_N<0>
  VSS37  = GND
  \lbd||rsp_a_n\  = M_I_CPU0_SA_RSP<0>
  \lbs||rsp_b_n\  = M_I_CPU0_SB_RSP<0>
  VSS38  = GND
  CB4_B  = M_I_CPU0_SB_CB<4>
  VSS39  = GND
  CB5_B  = M_I_CPU0_SB_CB<5>
  VSS40  = GND
  \dqs9_b_t||tdqs9_b_t||dbi4_b_n\  = M_I_CPU0_SB_DQS_DP<9>
  \dqs9_b_c||tdqs9_b_c\  = M_I_CPU0_SB_DQS_DN<9>
  VSS41  = GND
  CB0_B  = M_I_CPU0_SB_CB<0>
  VSS42  = GND
  CB1_B  = M_I_CPU0_SB_CB<1>
  VSS43  = GND
  DQ0_B  = M_I_CPU0_SB_DQ<0>
  VSS44  = GND
  DQ1_B  = M_I_CPU0_SB_DQ<1>
  VSS45  = GND
  DQS0_B_T  = M_I_CPU0_SB_DQS_DP<0>
  DQS0_B_C  = M_I_CPU0_SB_DQS_DN<0>
  VSS46  = GND
  DQ4_B  = M_I_CPU0_SB_DQ<4>
  VSS47  = GND
  DQ5_B  = M_I_CPU0_SB_DQ<5>
  VSS48  = GND
  DQ8_B  = M_I_CPU0_SB_DQ<8>
  VSS49  = GND
  DQ9_B  = M_I_CPU0_SB_DQ<9>
  VSS50  = GND
  DQS1_B_T  = M_I_CPU0_SB_DQS_DP<1>
  DQS1_B_C  = M_I_CPU0_SB_DQS_DN<1>
  VSS51  = GND
  DQ12_B  = M_I_CPU0_SB_DQ<12>
  VSS52  = GND
  DQ13_B  = M_I_CPU0_SB_DQ<13>
  VSS53  = GND
  DQ16_B  = M_I_CPU0_SB_DQ<16>
  VSS54  = GND
  DQ17_B  = M_I_CPU0_SB_DQ<17>
  VSS55  = GND
  DQS2_B_T  = M_I_CPU0_SB_DQS_DP<2>
  DQS2_B_C  = M_I_CPU0_SB_DQS_DN<2>
  VSS56  = GND
  DQ20_B  = M_I_CPU0_SB_DQ<20>
  VSS57  = GND
  DQ21_B  = M_I_CPU0_SB_DQ<21>
  VSS58  = GND
  DQ24_B  = M_I_CPU0_SB_DQ<24>
  VSS59  = GND
  DQ25_B  = M_I_CPU0_SB_DQ<25>
  VSS60  = GND
  DQS3_B_T  = M_I_CPU0_SB_DQS_DP<3>
  DQS3_B_C  = M_I_CPU0_SB_DQS_DN<3>
  VSS61  = GND
  DQ28_B  = M_I_CPU0_SB_DQ<28>
  VSS62  = GND
  DQ29_B  = M_I_CPU0_SB_DQ<29>
  VSS63  = GND
  RFU1  = NC
  VIN_BULK1  = P12V_MEM_CPU0
  VIN_BULK2  = P12V_MEM_CPU0
  \pwr_good||fail_n\  = PWRGD_CHI_CPU0_DIMM
  HAS  = PD_CHI_CPU0_DIMM_SAA
  RFU2  = NC
  RFU3  = NC
  VSS64  = GND
  DQ2_A  = M_I_CPU0_SA_DQ<2>
  VSS65  = GND
  DQ3_A  = M_I_CPU0_SA_DQ<3>
  VSS66  = GND
  \dqs5_a_c||tdqs5_a_c||dqs5_a_t||tdqs5_a_t\  = M_I_CPU0_SA_DQS_DN<5>
  \dqs5_a_t||tdqs5_a_t\  = M_I_CPU0_SA_DQS_DP<5>
  VSS67  = GND
  DQ6_A  = M_I_CPU0_SA_DQ<6>
  VSS68  = GND
  DQ7_A  = M_I_CPU0_SA_DQ<7>
  VSS69  = GND
  DQ10_A  = M_I_CPU0_SA_DQ<10>
  VSS70  = GND
  DQ11_A  = M_I_CPU0_SA_DQ<11>
  VSS71  = GND
  \dqs6_a_c||tdqs6_a_c||dqs6_a_t||tdqs6_a_t\  = M_I_CPU0_SA_DQS_DN<6>
  \dqs6_a_t||tdqs6_a_t\  = M_I_CPU0_SA_DQS_DP<6>
  VSS72  = GND
  DQ14_A  = M_I_CPU0_SA_DQ<14>
  VSS73  = GND
  DQ15_A  = M_I_CPU0_SA_DQ<15>
  VSS74  = GND
  DQ18_A  = M_I_CPU0_SA_DQ<18>
  VSS75  = GND
  DQ19_A  = M_I_CPU0_SA_DQ<19>
  VSS76  = GND
  \dqs7_a_c||tdqs7_a_c\  = M_I_CPU0_SA_DQS_DN<7>
  \dqs7_a_t||tdqs7_a_t\  = M_I_CPU0_SA_DQS_DP<7>
  VSS77  = GND
  DQ22_A  = M_I_CPU0_SA_DQ<22>
  VSS78  = GND
  DQ23_A  = M_I_CPU0_SA_DQ<23>
  VSS79  = GND
  DQ26_A  = M_I_CPU0_SA_DQ<26>
  VSS80  = GND
  DQ27_A  = M_I_CPU0_SA_DQ<27>
  VSS81  = GND
  \dqs8_a_c||tdqs8_a_c\  = M_I_CPU0_SA_DQS_DN<8>
  \dqs8_a_t||tdqs8_a_t\  = M_I_CPU0_SA_DQS_DP<8>
  VSS82  = GND
  DQ30_A  = M_I_CPU0_SA_DQ<30>
  VSS83  = GND
  DQ31_A  = M_I_CPU0_SA_DQ<31>
  VSS84  = GND
  CB2_A  = M_I_CPU0_SA_CB<2>
  VSS85  = GND
  CB3_A  = M_I_CPU0_SA_CB<3>
  VSS86  = GND
  \dqs9_a_c||tdqs9_a_c\  = M_I_CPU0_SA_DQS_DN<9>
  \dqs9_a_t||tdqs9_a_t\  = M_I_CPU0_SA_DQS_DP<9>
  VSS87  = GND
  CB6_A  = M_I_CPU0_SA_CB<6>
  VSS88  = GND
  CB7_A  = M_I_CPU0_SA_CB<7>
  VSS89  = GND
  RESET_N  = M_I_CPU0_RESET_N
  VSS90  = GND
  CS1_A_N  = M_I_CPU0_SA_CS_N<1>
  VSS91  = GND
  CA1_A  = M_I_CPU0_SA_CA<1>
  VSS92  = GND
  CA3_A  = M_I_CPU0_SA_CA<3>
  VSS93  = GND
  CA5_A  = M_I_CPU0_SA_CA<5>
  VSS94  = GND
  CK_T  = M_I_CPU0_CLK_DP<0>
  CK_C  = M_I_CPU0_CLK_DN<0>
  VSS95  = GND
  RFU4  = NC
  CA1_B  = M_I_CPU0_SB_CA<1>
  VSS96  = GND
  CA3_B  = M_I_CPU0_SB_CA<3>
  VSS97  = GND
  CA5_B  = M_I_CPU0_SB_CA<5>
  VSS98  = GND
  PAR_B  = M_I_CPU0_SB_PAR
  VSS99  = GND
  CS1_B_N  = M_I_CPU0_SB_CS_N<1>
  VSS100  = GND
  RFU5  = NC
  RFU6  = NC
  VSS101  = GND
  CB6_B  = M_I_CPU0_SB_CB<6>
  VSS102  = GND
  CB7_B  = M_I_CPU0_SB_CB<7>
  VSS103  = GND
  DQS4_B_C  = M_I_CPU0_SB_DQS_DN<4>
  DQS4_B_T  = M_I_CPU0_SB_DQS_DP<4>
  VSS104  = GND
  CB2_B  = M_I_CPU0_SB_CB<2>
  VSS105  = GND
  CB3_B  = M_I_CPU0_SB_CB<3>
  VSS106  = GND
  DQ2_B  = M_I_CPU0_SB_DQ<2>
  VSS107  = GND
  DQ3_B  = M_I_CPU0_SB_DQ<3>
  VSS108  = GND
  \dqs5_b_c||tdqs5_b_c\  = M_I_CPU0_SB_DQS_DN<5>
  \dqs5_b_t||tdqs5_b_t\  = M_I_CPU0_SB_DQS_DP<5>
  VSS109  = GND
  DQ6_B  = M_I_CPU0_SB_DQ<6>
  VSS110  = GND
  DQ7_B  = M_I_CPU0_SB_DQ<7>
  VSS111  = GND
  DQ10_B  = M_I_CPU0_SB_DQ<10>
  VSS112  = GND
  DQ11_B  = M_I_CPU0_SB_DQ<11>
  VSS113  = GND
  \dqs6_b_c||tdqs6_b_c\  = M_I_CPU0_SB_DQS_DN<6>
  \dqs6_b_t||tdqs6_b_t\  = M_I_CPU0_SB_DQS_DP<6>
  VSS114  = GND
  DQ14_B  = M_I_CPU0_SB_DQ<14>
  VSS115  = GND
  DQ15_B  = M_I_CPU0_SB_DQ<15>
  VSS116  = GND
  DQ18_B  = M_I_CPU0_SB_DQ<18>
  VSS117  = GND
  DQ19_B  = M_I_CPU0_SB_DQ<19>
  VSS118  = GND
  \dqs7_b_c||tdqs7_b_c\  = M_I_CPU0_SB_DQS_DN<7>
  \dqs7_b_t||tdqs7_b_t\  = M_I_CPU0_SB_DQS_DP<7>
  VSS119  = GND
  DQ22_B  = M_I_CPU0_SB_DQ<22>
  VSS120  = GND
  DQ23_B  = M_I_CPU0_SB_DQ<23>
  VSS121  = GND
  DQ26_B  = M_I_CPU0_SB_DQ<26>
  VSS122  = GND
  DQ27_B  = M_I_CPU0_SB_DQ<27>
  VSS123  = GND
  \dqs8_b_c||tdqs8_b_c\  = M_I_CPU0_SB_DQS_DN<8>
  \dqs8_b_t||tdqs8_b_t\  = M_I_CPU0_SB_DQS_DP<8>
  VSS124  = GND
  DQ30_B  = M_I_CPU0_SB_DQ<30>
  VSS125  = GND
  DQ31_B  = M_I_CPU0_SB_DQ<31>
  VSS126  = GND
  G1  = GND
  G2  = GND
  G3  = GND

(kicad_pcb
	(version 20260206)
	(generator "pcbnew")
	(generator_version "10.0")
	(general
		(thickness 1.6)
		(legacy_teardrops no)
	)
	(paper "A4")
	(title_block
		(title "04192023_DAF0TMB3IC0_F0TG_MB_C_brd_V02_OCP.brd")
		(comment 1 "Grand Teton / footprint 4761 of 8354 (J18), pads 47-92 of 291")
	)
	(layers
		(0 "F.Cu" signal "TOP")
		(4 "In1.Cu" signal "GND")
		(6 "In2.Cu" signal "IN1")
		(8 "In3.Cu" signal "GND1")
		(10 "In4.Cu" signal "IN2")
		(12 "In5.Cu" signal "GND2")
		(14 "In6.Cu" signal "IN3")
		(16 "In7.Cu" signal "GND3")
		(18 "In8.Cu" signal "VCC")
		(20 "In9.Cu" signal "VCC1")
		(22 "In10.Cu" signal "GND4")
		(24 "In11.Cu" signal "IN4")
		(26 "In12.Cu" signal "GND5")
		(28 "In13.Cu" signal "IN5")
		(30 "In14.Cu" signal "GND6")
		(32 "In15.Cu" signal "IN6")
		(34 "In16.Cu" signal "GND7")
		(2 "B.Cu" signal "BOTTOM")
		(9 "F.Adhes" user "F.Adhesive")
		(11 "B.Adhes" user "B.Adhesive")
		(13 "F.Paste" user "Package Geometry/Pastemask Top")
		(15 "B.Paste" user "Package Geometry/Pastemask Bottom")
		(5 "F.SilkS" user "Ref Des/Silkscreen Top")
		(7 "B.SilkS" user "Ref Des/Silkscreen Bottom")
		(1 "F.Mask" user "Board Geometry/Soldermask Top")
		(3 "B.Mask" user "Board Geometry/Soldermask Bottom")
		(17 "Dwgs.User" user "User.Drawings")
		(19 "Cmts.User" user "User.Comments")
		(21 "Eco1.User" user "User.Eco1")
		(23 "Eco2.User" user "User.Eco2")
		(25 "Edge.Cuts" user "Board Geometry/Outline")
		(27 "Margin" user)
		(31 "F.CrtYd" user "Package Geometry/Place Bound Top")
		(29 "B.CrtYd" user "Package Geometry/Place Bound Bottom")
		(35 "F.Fab" user "Ref Des/Assembly Top")
		(33 "B.Fab" user "Ref Des/Assembly Bottom")
	)
	(footprint ""
		(layer "F.Cu")
		(at 429.506126 -255.560068 180)
		(property "Reference" "J18"
			(at 0.484632 -81.752948 0)
			(unlocked yes)
			(layer "F.SilkS")
			(effects
				(font
					(size 0.7874 0.5842)
					(thickness 0.1524)
				)
			)
		)
		(property "Value" ""
			(at 0 0 180)
			(layer "F.Fab")
			(effects
				(font
					(size 1.27 1.27)
				)
			)
		)
		(duplicate_pad_numbers_are_jumpers no)
		(pad "47" smd rect
			(at -2.050034 -24.224996 90)
			(size 0.519938 1.4986)
			(layers "F.Cu" "F.Mask" "F.Paste")
			(net "M_I_CPU0_SA_DQ<28>")
		)
		(pad "48" smd rect
			(at -2.050034 -23.375112 90)
			(size 0.519938 1.4986)
			(layers "F.Cu" "F.Mask" "F.Paste")
			(net "GND")
		)
		(pad "49" smd rect
			(at -2.050034 -22.524974 90)
			(size 0.519938 1.4986)
			(layers "F.Cu" "F.Mask" "F.Paste")
			(net "M_I_CPU0_SA_DQ<29>")
		)
		(pad "50" smd rect
			(at -2.050034 -21.67509 90)
			(size 0.519938 1.4986)
			(layers "F.Cu" "F.Mask" "F.Paste")
			(net "GND")
		)
		(pad "51" smd rect
			(at -2.050034 -20.824952 90)
			(size 0.519938 1.4986)
			(layers "F.Cu" "F.Mask" "F.Paste")
			(net "M_I_CPU0_SA_CB<0>")
		)
		(pad "52" smd rect
			(at -2.050034 -19.975068 90)
			(size 0.519938 1.4986)
			(layers "F.Cu" "F.Mask" "F.Paste")
			(net "GND")
		)
		(pad "53" smd rect
			(at -2.050034 -19.12493 90)
			(size 0.519938 1.4986)
			(layers "F.Cu" "F.Mask" "F.Paste")
			(net "M_I_CPU0_SA_CB<1>")
		)
		(pad "54" smd rect
			(at -2.050034 -18.275046 90)
			(size 0.519938 1.4986)
			(layers "F.Cu" "F.Mask" "F.Paste")
			(net "GND")
		)
		(pad "55" smd rect
			(at -2.050034 -17.424908 90)
			(size 0.519938 1.4986)
			(layers "F.Cu" "F.Mask" "F.Paste")
			(net "M_I_CPU0_SA_DQS_DP<4>")
		)
		(pad "56" smd rect
			(at -2.050034 -16.575024 90)
			(size 0.519938 1.4986)
			(layers "F.Cu" "F.Mask" "F.Paste")
			(net "M_I_CPU0_SA_DQS_DN<4>")
		)
		(pad "57" smd rect
			(at -2.050034 -15.724886 90)
			(size 0.519938 1.4986)
			(layers "F.Cu" "F.Mask" "F.Paste")
			(net "GND")
		)
		(pad "58" smd rect
			(at -2.050034 -14.875002 90)
			(size 0.519938 1.4986)
			(layers "F.Cu" "F.Mask" "F.Paste")
			(net "M_I_CPU0_SA_CB<4>")
		)
		(pad "59" smd rect
			(at -2.050034 -14.025118 90)
			(size 0.519938 1.4986)
			(layers "F.Cu" "F.Mask" "F.Paste")
			(net "GND")
		)
		(pad "60" smd rect
			(at -2.050034 -13.17498 90)
			(size 0.519938 1.4986)
			(layers "F.Cu" "F.Mask" "F.Paste")
			(net "M_I_CPU0_SA_CB<5>")
		)
		(pad "61" smd rect
			(at -2.050034 -12.325096 90)
			(size 0.519938 1.4986)
			(layers "F.Cu" "F.Mask" "F.Paste")
			(net "GND")
		)
		(pad "62" smd rect
			(at -2.050034 -11.474958 90)
			(size 0.519938 1.4986)
			(layers "F.Cu" "F.Mask" "F.Paste")
			(net "M_I_CPU0_ALERT_N")
		)
		(pad "63" smd rect
			(at -2.050034 -10.625074 90)
			(size 0.519938 1.4986)
			(layers "F.Cu" "F.Mask" "F.Paste")
			(net "GND")
		)
		(pad "64" smd rect
			(at -2.050034 -9.774936 90)
			(size 0.519938 1.4986)
			(layers "F.Cu" "F.Mask" "F.Paste")
			(net "M_I_CPU0_SA_CS_N<0>")
		)
		(pad "65" smd rect
			(at -2.050034 -8.925052 90)
			(size 0.519938 1.4986)
			(layers "F.Cu" "F.Mask" "F.Paste")
			(net "GND")
		)
		(pad "66" smd rect
			(at -2.050034 -8.074914 90)
			(size 0.519938 1.4986)
			(layers "F.Cu" "F.Mask" "F.Paste")
			(net "M_I_CPU0_SA_CA<0>")
		)
		(pad "67" smd rect
			(at -2.050034 -7.22503 90)
			(size 0.519938 1.4986)
			(layers "F.Cu" "F.Mask" "F.Paste")
			(net "GND")
		)
		(pad "68" smd rect
			(at -2.050034 -6.374892 90)
			(size 0.519938 1.4986)
			(layers "F.Cu" "F.Mask" "F.Paste")
			(net "M_I_CPU0_SA_CA<2>")
		)
		(pad "69" smd rect
			(at -2.050034 -5.525008 90)
			(size 0.519938 1.4986)
			(layers "F.Cu" "F.Mask" "F.Paste")
			(net "GND")
		)
		(pad "70" smd rect
			(at -2.050034 -4.675124 90)
			(size 0.519938 1.4986)
			(layers "F.Cu" "F.Mask" "F.Paste")
			(net "M_I_CPU0_SA_CA<4>")
		)
		(pad "71" smd rect
			(at -2.050034 -3.824986 90)
			(size 0.519938 1.4986)
			(layers "F.Cu" "F.Mask" "F.Paste")
			(net "GND")
		)
		(pad "72" smd rect
			(at -2.050034 -2.975102 90)
			(size 0.519938 1.4986)
			(layers "F.Cu" "F.Mask" "F.Paste")
			(net "M_I_CPU0_SA_CA<6>")
		)
		(pad "73" smd rect
			(at -2.050034 -2.124964 90)
			(size 0.519938 1.4986)
			(layers "F.Cu" "F.Mask" "F.Paste")
			(net "GND")
		)
		(pad "74" smd rect
			(at -2.050034 -1.27508 90)
			(size 0.519938 1.4986)
			(layers "F.Cu" "F.Mask" "F.Paste")
			(net "M_I_CPU0_SA_PAR")
		)
		(pad "75" smd rect
			(at -2.050034 -0.424942 90)
			(size 0.519938 1.4986)
			(layers "F.Cu" "F.Mask" "F.Paste")
			(net "GND")
		)
		(pad "76" smd rect
			(at -2.050034 5.525008 90)
			(size 0.519938 1.4986)
			(layers "F.Cu" "F.Mask" "F.Paste")
			(net "M_I_CPU0_SB_CA<0>")
		)
		(pad "77" smd rect
			(at -2.050034 6.374892 90)
			(size 0.519938 1.4986)
			(layers "F.Cu" "F.Mask" "F.Paste")
			(net "GND")
		)
		(pad "78" smd rect
			(at -2.050034 7.22503 90)
			(size 0.519938 1.4986)
			(layers "F.Cu" "F.Mask" "F.Paste")
			(net "M_I_CPU0_SB_CA<2>")
		)
		(pad "79" smd rect
			(at -2.050034 8.074914 90)
			(size 0.519938 1.4986)
			(layers "F.Cu" "F.Mask" "F.Paste")
			(net "GND")
		)
		(pad "80" smd rect
			(at -2.050034 8.925052 90)
			(size 0.519938 1.4986)
			(layers "F.Cu" "F.Mask" "F.Paste")
			(net "M_I_CPU0_SB_CA<4>")
		)
		(pad "81" smd rect
			(at -2.050034 9.774936 90)
			(size 0.519938 1.4986)
			(layers "F.Cu" "F.Mask" "F.Paste")
			(net "GND")
		)
		(pad "82" smd rect
			(at -2.050034 10.625074 90)
			(size 0.519938 1.4986)
			(layers "F.Cu" "F.Mask" "F.Paste")
			(net "M_I_CPU0_SB_CA<6>")
		)
		(pad "83" smd rect
			(at -2.050034 11.474958 90)
			(size 0.519938 1.4986)
			(layers "F.Cu" "F.Mask" "F.Paste")
			(net "GND")
		)
		(pad "84" smd rect
			(at -2.050034 12.325096 90)
			(size 0.519938 1.4986)
			(layers "F.Cu" "F.Mask" "F.Paste")
			(net "M_I_CPU0_SB_CS_N<0>")
		)
		(pad "85" smd rect
			(at -2.050034 13.17498 90)
			(size 0.519938 1.4986)
			(layers "F.Cu" "F.Mask" "F.Paste")
			(net "GND")
		)
		(pad "86" smd rect
			(at -2.050034 14.025118 90)
			(size 0.519938 1.4986)
			(layers "F.Cu" "F.Mask" "F.Paste")
			(net "M_I_CPU0_SA_RSP<0>")
		)
		(pad "87" smd rect
			(at -2.050034 14.875002 90)
			(size 0.519938 1.4986)
			(layers "F.Cu" "F.Mask" "F.Paste")
			(net "M_I_CPU0_SB_RSP<0>")
		)
		(pad "88" smd rect
			(at -2.050034 15.724886 90)
			(size 0.519938 1.4986)
			(layers "F.Cu" "F.Mask" "F.Paste")
			(net "GND")
		)
		(pad "89" smd rect
			(at -2.050034 16.575024 90)
			(size 0.519938 1.4986)
			(layers "F.Cu" "F.Mask" "F.Paste")
			(net "M_I_CPU0_SB_CB<4>")
		)
		(pad "90" smd rect
			(at -2.050034 17.424908 90)
			(size 0.519938 1.4986)
			(layers "F.Cu" "F.Mask" "F.Paste")
			(net "GND")
		)
		(pad "91" smd rect
			(at -2.050034 18.275046 90)
			(size 0.519938 1.4986)
			(layers "F.Cu" "F.Mask" "F.Paste")
			(net "M_I_CPU0_SB_CB<5>")
		)
		(pad "92" smd rect
			(at -2.050034 19.12493 90)
			(size 0.519938 1.4986)
			(layers "F.Cu" "F.Mask" "F.Paste")
			(net "GND")
		)
	)
)
